# TIMECARD (Time Appliance Project (Time Card)) — schematic netlist excerpt (pin names and nets, part order shuffled) for the footprints in the layout excerpt that follows; sources: Cadence DE-HDL packaged netlist, KiCad conversion of R4006-B0001-02_R01.brd

R194  RESISTOR  4.7KOHM 1%  pkg SMC_0402R_H016  page 10 : \1\ = XP3R3V_FPGA ; \2\ = CFGBVS
ME4  NUT  pkg P_NUT_166CT244CB198_V1_H380  page 34 : \1\ = SG

(kicad_pcb
	(version 20260206)
	(generator "pcbnew")
	(generator_version "10.0")
	(general
		(thickness 1.6)
		(legacy_teardrops no)
	)
	(paper "A4")
	(title_block
		(title "timecard-production-celestica-r4006 — R4006-B0001-02_R01.brd")
		(comment 1 "Time Appliance Project (Time Card) / footprints 377-378 of 1113")
	)
	(layers
		(0 "F.Cu" signal "TOP")
		(4 "In1.Cu" signal "L02_GND1")
		(6 "In2.Cu" signal "L03_SIG1")
		(8 "In3.Cu" signal "L04_GND2")
		(10 "In4.Cu" signal "L05_VCC1")
		(12 "In5.Cu" signal "L06_VCC2")
		(14 "In6.Cu" signal "L07_GND3")
		(16 "In7.Cu" signal "L08_SIG2")
		(18 "In8.Cu" signal "L09_GND4")
		(2 "B.Cu" signal "BOTTOM")
		(9 "F.Adhes" user "F.Adhesive")
		(11 "B.Adhes" user "B.Adhesive")
		(13 "F.Paste" user "Package Geometry/Pastemask Top")
		(15 "B.Paste" user "Package Geometry/Pastemask Bottom")
		(5 "F.SilkS" user "Ref Des/Silkscreen Top")
		(7 "B.SilkS" user "Ref Des/Silkscreen Bottom")
		(1 "F.Mask" user "Board Geometry/Soldermask Top")
		(3 "B.Mask" user "Board Geometry/Soldermask Bottom")
		(17 "Dwgs.User" user "User.Drawings")
		(19 "Cmts.User" user "User.Comments")
		(21 "Eco1.User" user "User.Eco1")
		(23 "Eco2.User" user "User.Eco2")
		(25 "Edge.Cuts" user "Board Geometry/Outline")
		(27 "Margin" user)
		(31 "F.CrtYd" user "Package Geometry/Place Bound Top")
		(29 "B.CrtYd" user "Package Geometry/Place Bound Bottom")
		(35 "F.Fab" user "Ref Des/Assembly Top")
		(33 "B.Fab" user "Ref Des/Assembly Bottom")
	)
	(footprint ""
		(layer "F.Cu")
		(at 126.492 -33.909 180)
		(property "Reference" "R194"
			(at -2.921 -1.43637 0)
			(unlocked yes)
			(layer "F.SilkS")
			(effects
				(font
					(size 0.7874 0.5842)
					(thickness 0.1524)
				)
			)
		)
		(property "Value" "VAL*"
			(at 0.02032 2.13233 180)
			(unlocked yes)
			(layer "F.Fab")
			(hide yes)
			(effects
				(font
					(size 0.7874 0.5842)
					(thickness 0.1524)
				)
			)
		)
		(property "Tolerance" "TOL*"
			(at 0.044704 3.05435 180)
			(unlocked yes)
			(layer "Cmts.User")
			(hide yes)
			(effects
				(font
					(size 0.7874 0.5842)
					(thickness 0.1524)
				)
			)
		)
		(property "User Part Number" "PARTNUM*"
			(at 0.02032 4.024884 180)
			(unlocked yes)
			(layer "Cmts.User")
			(hide yes)
			(effects
				(font
					(size 0.7874 0.5842)
					(thickness 0.1524)
				)
			)
		)
		(property "Device Type" "RESISTOR-G155-14701-01,4.7KOHMA"
			(at 0.008382 1.210564 180)
			(unlocked yes)
			(layer "F.Fab")
			(hide yes)
			(effects
				(font
					(size 0.7874 0.5842)
					(thickness 0.1524)
				)
			)
		)
		(duplicate_pad_numbers_are_jumpers no)
		(fp_line
			(start 1.143 0.5588)
			(end 1.143 -0.5588)
			(stroke
				(width 0.1)
				(type default)
			)
			(layer "F.SilkS")
		)
		(fp_line
			(start 1.143 -0.5588)
			(end -1.143 -0.5588)
			(stroke
				(width 0.1)
				(type default)
			)
			(layer "F.SilkS")
		)
		(fp_line
			(start -1.143 0.5588)
			(end 1.143 0.5588)
			(stroke
				(width 0.1)
				(type default)
			)
			(layer "F.SilkS")
		)
		(fp_line
			(start -1.143 -0.5588)
			(end -1.143 0.5588)
			(stroke
				(width 0.1)
				(type default)
			)
			(layer "F.SilkS")
		)
		(fp_rect
			(start 1.143 0.5588)
			(end -1.143 -0.5588)
			(stroke
				(width 0)
				(type default)
			)
			(fill no)
			(layer "F.CrtYd")
		)
		(fp_line
			(start 0.508 0.3048)
			(end 0.508 -0.3048)
			(stroke
				(width 0.1)
				(type default)
			)
			(layer "F.Fab")
		)
		(fp_line
			(start 0.508 -0.3048)
			(end -0.508 -0.3048)
			(stroke
				(width 0.1)
				(type default)
			)
			(layer "F.Fab")
		)
		(fp_line
			(start -0.508 0.3048)
			(end 0.508 0.3048)
			(stroke
				(width 0.1)
				(type default)
			)
			(layer "F.Fab")
		)
		(fp_line
			(start -0.508 -0.3048)
			(end -0.508 0.3048)
			(stroke
				(width 0.1)
				(type default)
			)
			(layer "F.Fab")
		)
		(pad "1" smd rect
			(at -0.5334 0 180)
			(size 0.7112 0.6096)
			(layers "F.Cu" "F.Mask" "F.Paste")
			(net "XP3R3V_FPGA")
		)
		(pad "2" smd rect
			(at 0.5334 0 180)
			(size 0.7112 0.6096)
			(layers "F.Cu" "F.Mask" "F.Paste")
			(net "CFGBVS")
		)
		(zone
			(layer "F.Cu")
			(hatch none 0.5)
			(connect_pads
				(clearance 0)
			)
			(min_thickness 0.25)
			(keepout
				(tracks allowed)
				(vias not_allowed)
				(pads allowed)
				(copperpour not_allowed)
				(footprints allowed)
			)
			(placement
				(enabled no)
				(sheetname "")
			)
			(fill
				(thermal_gap 0.5)
				(thermal_bridge_width 0.5)
				(island_removal_mode 0)
			)
			(polygon
				(pts
					(xy 126.4158 -34.2138) (xy 126.4158 -33.6042) (xy 126.5682 -33.6042) (xy 126.5682 -34.2138)
				)
			)
		)
	)
	(footprint ""
		(layer "F.Cu")
		(at 125.499876 -78.650084)
		(property "Reference" "ME4"
			(at -1.230376 -4.114546 0)
			(unlocked yes)
			(layer "F.SilkS")
			(effects
				(font
					(size 0.7874 0.5842)
					(thickness 0.1524)
				)
				(justify left)
			)
		)
		(property "Value" ""
			(at 0 0 0)
			(layer "F.Fab")
			(effects
				(font
					(size 1.27 1.27)
				)
			)
		)
		(property "User Part Number" "PARTNUM*"
			(at -3.048 5.242306 0)
			(unlocked yes)
			(layer "Cmts.User")
			(hide yes)
			(effects
				(font
					(size 0.7874 0.5842)
					(thickness 0.1524)
				)
				(justify left)
			)
		)
		(property "Device Type" "NUT-G340-10437-01"
			(at -1.4732 4.226306 0)
			(unlocked yes)
			(layer "F.Fab")
			(hide yes)
			(effects
				(font
					(size 0.7874 0.5842)
					(thickness 0.1524)
				)
				(justify left)
			)
		)
		(duplicate_pad_numbers_are_jumpers no)
		(fp_circle
			(center 0 0)
			(end 3.3528 0)
			(stroke
				(width 0.1)
				(type default)
			)
			(fill no)
			(layer "F.SilkS")
		)
		(fp_poly
			(pts
				(arc
					(start -2.102612 -0.1524)
					(mid -1.490671 -1.490671)
					(end -0.1524 -2.102612)
				)
				(arc
					(start -0.1524 -3.171444)
					(mid -2.245137 -2.245137)
					(end -3.171444 -0.1524)
				)
			)
			(stroke
				(width 0)
				(type default)
			)
			(fill yes)
			(layer "F.Paste")
		)
		(fp_poly
			(pts
				(arc
					(start -0.1524 2.102612)
					(mid -1.490671 1.490671)
					(end -2.102612 0.1524)
				)
				(arc
					(start -3.171444 0.1524)
					(mid -2.245137 2.245137)
					(end -0.1524 3.171444)
				)
			)
			(stroke
				(width 0)
				(type default)
			)
			(fill yes)
			(layer "F.Paste")
		)
		(fp_poly
			(pts
				(arc
					(start 0.1524 -2.102612)
					(mid 1.490671 -1.490671)
					(end 2.102612 -0.1524)
				)
				(arc
					(start 3.171444 -0.1524)
					(mid 2.245137 -2.245137)
					(end 0.1524 -3.171444)
				)
			)
			(stroke
				(width 0)
				(type default)
			)
			(fill yes)
			(layer "F.Paste")
		)
		(fp_poly
			(pts
				(arc
					(start 2.102612 0.1524)
					(mid 1.490671 1.490671)
					(end 0.1524 2.102612)
				)
				(arc
					(start 0.1524 3.171444)
					(mid 2.245137 2.245137)
					(end 3.171444 0.1524)
				)
			)
			(stroke
				(width 0)
				(type default)
			)
			(fill yes)
			(layer "F.Paste")
		)
		(fp_rect
			(start -7.5946 7.5946)
			(end 7.5946 -7.5946)
			(stroke
				(width 0)
				(type default)
			)
			(fill no)
			(layer "B.CrtYd")
		)
		(fp_poly
			(pts
				(arc
					(start 3.6068 0)
					(mid -3.6068 0)
					(end 3.6068 0)
				)
			)
			(stroke
				(width 0)
				(type default)
			)
			(fill no)
			(layer "F.CrtYd")
		)
		(fp_circle
			(center 0 0)
			(end 2.8448 0)
			(stroke
				(width 0.1)
				(type default)
			)
			(fill no)
			(layer "F.Fab")
		)
		(pad "1" thru_hole circle
			(at 0 0)
			(size 6.1976 6.1976)
			(drill 4.2164)
			(layers "*.Cu" "*.Mask")
			(remove_unused_layers no)
			(net "SG")
			(padstack
				(mode front_inner_back)
				(layer "Inner"
					(shape circle)
					(size 5.0292 5.0292)
					(clearance -0.1143)
				)
				(layer "B.Cu"
					(shape circle)
					(size 5.0292 5.0292)
				)
			)
		)
	)
)
